# S9S_MB_2U (Grand Teton) — schematic netlist excerpt (pin names and nets, part order shuffled) for the footprints in the layout excerpt that follows; sources: Cadence DE-HDL packaged netlist, KiCad conversion of 03242023_DA0F0TMBIJ0_F0T_Motherboard_J_brd_V01_OCP.brd

J14  SCONN288_ADR50017P087CC  SCONN288_ADR50017-P087CC IO  pkg DDR288S_1-1VXB  page 95
  VIN_BULK0  = P12V_S3_AUX_CPU0_NVDIMM
  RFU0  = TP_CHG_CPU0_DIMM2_FRU_0
  VIN_MGMT  = P3V3_AUX
  HSCL  = I3C_SPD_DDREFGH_CPU0_LVC1_SCL_5
  HSDA  = I3C_SPD_DDREFGH_CPU0_LVC1_SDA
  VSS0  = GND
  DQ0_A  = M_G_CPU0_SA_DQ<0>
  VSS1  = GND
  DQ1_A  = M_G_CPU0_SA_DQ<1>
  VSS2  = GND
  DQS0_A_T  = M_G_CPU0_SA_DQS_DP<0>
  DQS0_A_C  = M_G_CPU0_SA_DQS_DN<0>
  VSS3  = GND
  DQ4_A  = M_G_CPU0_SA_DQ<4>
  VSS4  = GND
  DQ5_A  = M_G_CPU0_SA_DQ<5>
  VSS5  = GND
  DQ8_A  = M_G_CPU0_SA_DQ<8>
  VSS6  = GND
  DQ9_A  = M_G_CPU0_SA_DQ<9>
  VSS7  = GND
  DQS1_A_T  = M_G_CPU0_SA_DQS_DP<1>
  DQS1_A_C  = M_G_CPU0_SA_DQS_DN<1>
  VSS8  = GND
  DQ12_A  = M_G_CPU0_SA_DQ<12>
  VSS9  = GND
  DQ13_A  = M_G_CPU0_SA_DQ<13>
  VSS10  = GND
  DQ16_A  = M_G_CPU0_SA_DQ<16>
  VSS11  = GND
  DQ17_A  = M_G_CPU0_SA_DQ<17>
  VSS12  = GND
  DQS2_A_T  = M_G_CPU0_SA_DQS_DP<2>
  DQS2_A_C  = M_G_CPU0_SA_DQS_DN<2>
  VSS13  = GND
  DQ20_A  = M_G_CPU0_SA_DQ<20>
  VSS14  = GND
  DQ21_A  = M_G_CPU0_SA_DQ<21>
  VSS15  = GND
  DQ24_A  = M_G_CPU0_SA_DQ<24>
  VSS16  = GND
  DQ25_A  = M_G_CPU0_SA_DQ<25>
  VSS17  = GND
  DQS3_A_T  = M_G_CPU0_SA_DQS_DP<3>
  DQS3_A_C  = M_G_CPU0_SA_DQS_DN<3>
  VSS18  = GND
  DQ28_A  = M_G_CPU0_SA_DQ<28>
  VSS19  = GND
  DQ29_A  = M_G_CPU0_SA_DQ<29>
  VSS20  = GND
  CB0_A  = M_G_CPU0_SA_CB<0>
  VSS21  = GND
  CB1_A  = M_G_CPU0_SA_CB<1>
  VSS22  = GND
  DQS4_A_T  = M_G_CPU0_SA_DQS_DP<4>
  DQS4_A_C  = M_G_CPU0_SA_DQS_DN<4>
  VSS23  = GND
  CB4_A  = M_G_CPU0_SA_CB<4>
  VSS24  = GND
  CB5_A  = M_G_CPU0_SA_CB<5>
  VSS25  = GND
  ALERT_N  = M_G_CPU0_ALERT_N
  VSS26  = GND
  CS0_A_N  = M_G_CPU0_SA_CS_N<2>
  VSS27  = GND
  CA0_A  = M_G_CPU0_SA_CA<0>
  VSS28  = GND
  CA2_A  = M_G_CPU0_SA_CA<2>
  VSS29  = GND
  CA4_A  = M_G_CPU0_SA_CA<4>
  VSS30  = GND
  CA6_A  = M_G_CPU0_SA_CA<6>
  VSS31  = GND
  PAR_A  = M_G_CPU0_SA_PAR
  VSS32  = GND
  CA0_B  = M_G_CPU0_SB_CA<0>
  VSS33  = GND
  CA2_B  = M_G_CPU0_SB_CA<2>
  VSS34  = GND
  CA4_B  = M_G_CPU0_SB_CA<4>
  VSS35  = GND
  CA6_B  = M_G_CPU0_SB_CA<6>
  VSS36  = GND
  CS0_B_N  = M_G_CPU0_SB_CS_N<2>
  VSS37  = GND
  \lbd||rsp_a_n\  = M_G_CPU0_SA_RSP<1>
  \lbs||rsp_b_n\  = M_G_CPU0_SB_RSP<1>
  VSS38  = GND
  CB4_B  = M_G_CPU0_SB_CB<4>
  VSS39  = GND
  CB5_B  = M_G_CPU0_SB_CB<5>
  VSS40  = GND
  \dqs9_b_t||tdqs9_b_t||dbi4_b_n\  = M_G_CPU0_SB_DQS_DP<9>
  \dqs9_b_c||tdqs9_b_c\  = M_G_CPU0_SB_DQS_DN<9>
  VSS41  = GND
  CB0_B  = M_G_CPU0_SB_CB<0>
  VSS42  = GND
  CB1_B  = M_G_CPU0_SB_CB<1>
  VSS43  = GND
  DQ0_B  = M_G_CPU0_SB_DQ<0>
  VSS44  = GND
  DQ1_B  = M_G_CPU0_SB_DQ<1>
  VSS45  = GND
  DQS0_B_T  = M_G_CPU0_SB_DQS_DP<0>
  DQS0_B_C  = M_G_CPU0_SB_DQS_DN<0>
  VSS46  = GND
  DQ4_B  = M_G_CPU0_SB_DQ<4>
  VSS47  = GND
  DQ5_B  = M_G_CPU0_SB_DQ<5>
  VSS48  = GND
  DQ8_B  = M_G_CPU0_SB_DQ<8>
  VSS49  = GND
  DQ9_B  = M_G_CPU0_SB_DQ<9>
  VSS50  = GND
  DQS1_B_T  = M_G_CPU0_SB_DQS_DP<1>
  DQS1_B_C  = M_G_CPU0_SB_DQS_DN<1>
  VSS51  = GND
  DQ12_B  = M_G_CPU0_SB_DQ<12>
  VSS52  = GND
  DQ13_B  = M_G_CPU0_SB_DQ<13>
  VSS53  = GND
  DQ16_B  = M_G_CPU0_SB_DQ<16>
  VSS54  = GND
  DQ17_B  = M_G_CPU0_SB_DQ<17>
  VSS55  = GND
  DQS2_B_T  = M_G_CPU0_SB_DQS_DP<2>
  DQS2_B_C  = M_G_CPU0_SB_DQS_DN<2>
  VSS56  = GND
  DQ20_B  = M_G_CPU0_SB_DQ<20>
  VSS57  = GND
  DQ21_B  = M_G_CPU0_SB_DQ<21>
  VSS58  = GND
  DQ24_B  = M_G_CPU0_SB_DQ<24>
  VSS59  = GND
  DQ25_B  = M_G_CPU0_SB_DQ<25>
  VSS60  = GND
  DQS3_B_T  = M_G_CPU0_SB_DQS_DP<3>
  DQS3_B_C  = M_G_CPU0_SB_DQS_DN<3>
  VSS61  = GND
  DQ28_B  = M_G_CPU0_SB_DQ<28>
  VSS62  = GND
  DQ29_B  = M_G_CPU0_SB_DQ<29>
  VSS63  = GND
  RFU1  = TP_CHG_CPU0_DIMM2_FRU_1
  VIN_BULK1  = P12V_S3_AUX_CPU0_NVDIMM
  VIN_BULK2  = P12V_S3_AUX_CPU0_NVDIMM
  \pwr_good||fail_n\  = PWRGD_CHG_CPU0_DIMM2
  HSA  = PD_CHG_CPU0_DIMM2_SAA
  RFU2  = TP_CHG_CPU0_DIMM2_FRU_2
  RFU3  = TP_CHG_CPU0_DIMM2_FRU_3
  VSS64  = GND
  DQ2_A  = M_G_CPU0_SA_DQ<2>
  VSS65  = GND
  DQ3_A  = M_G_CPU0_SA_DQ<3>
  VSS66  = GND
  \dqs5_a_c||tdqs5_a_c||dqs5_a_t||tdqs5_a_t\  = M_G_CPU0_SA_DQS_DN<5>
  \dqs5_a_t||tdqs5_a_t\  = M_G_CPU0_SA_DQS_DP<5>
  VSS67  = GND
  DQ6_A  = M_G_CPU0_SA_DQ<6>
  VSS68  = GND
  DQ7_A  = M_G_CPU0_SA_DQ<7>
  VSS69  = GND
  DQ10_A  = M_G_CPU0_SA_DQ<10>
  VSS70  = GND
  DQ11_A  = M_G_CPU0_SA_DQ<11>
  VSS71  = GND
  \dqs6_a_c||tdqs6_a_c||dqs6_a_t||tdqs6_a_t\  = M_G_CPU0_SA_DQS_DN<6>
  \dqs6_a_t||tdqs6_a_t\  = M_G_CPU0_SA_DQS_DP<6>
  VSS72  = GND
  DQ14_A  = M_G_CPU0_SA_DQ<14>
  VSS73  = GND
  DQ15_A  = M_G_CPU0_SA_DQ<15>
  VSS74  = GND
  DQ18_A  = M_G_CPU0_SA_DQ<18>
  VSS75  = GND
  DQ19_A  = M_G_CPU0_SA_DQ<19>
  VSS76  = GND
  \dqs7_a_c||tdqs7_a_c\  = M_G_CPU0_SA_DQS_DN<7>
  \dqs7_a_t||tdqs7_a_t\  = M_G_CPU0_SA_DQS_DP<7>
  VSS77  = GND
  DQ22_A  = M_G_CPU0_SA_DQ<22>
  VSS78  = GND
  DQ23_A  = M_G_CPU0_SA_DQ<23>
  VSS79  = GND
  DQ26_A  = M_G_CPU0_SA_DQ<26>
  VSS80  = GND
  DQ27_A  = M_G_CPU0_SA_DQ<27>
  VSS81  = GND
  \dqs8_a_c||tdqs8_a_c\  = M_G_CPU0_SA_DQS_DN<8>
  \dqs8_a_t||tdqs8_a_t\  = M_G_CPU0_SA_DQS_DP<8>
  VSS82  = GND
  DQ30_A  = M_G_CPU0_SA_DQ<30>
  VSS83  = GND
  DQ31_A  = M_G_CPU0_SA_DQ<31>
  VSS84  = GND
  CB2_A  = M_G_CPU0_SA_CB<2>
  VSS85  = GND
  CB3_A  = M_G_CPU0_SA_CB<3>
  VSS86  = GND
  \dqs9_a_c||tdqs9_a_c\  = M_G_CPU0_SA_DQS_DN<9>
  \dqs9_a_t||tdqs9_a_t\  = M_G_CPU0_SA_DQS_DP<9>
  VSS87  = GND
  CB6_A  = M_G_CPU0_SA_CB<6>
  VSS88  = GND
  CB7_A  = M_G_CPU0_SA_CB<7>
  VSS89  = GND
  RESET_N  = RST_M_GH_CPU0_FPGA_N
  VSS90  = GND
  CS1_A_N  = M_G_CPU0_SA_CS_N<3>
  VSS91  = GND
  CA1_A  = M_G_CPU0_SA_CA<1>
  VSS92  = GND
  CA3_A  = M_G_CPU0_SA_CA<3>
  VSS93  = GND
  CA5_A  = M_G_CPU0_SA_CA<5>
  VSS94  = GND
  CK_T  = M_G_CPU0_CLK_DP<1>
  CK_C  = M_G_CPU0_CLK_DN<1>
  VSS95  = GND
  RFU4  = TP_CHG_CPU0_DIMM2_FRU_4
  CA1_B  = M_G_CPU0_SB_CA<1>
  VSS96  = GND
  CA3_B  = M_G_CPU0_SB_CA<3>
  VSS97  = GND
  CA5_B  = M_G_CPU0_SB_CA<5>
  VSS98  = GND
  PAR_B  = M_G_CPU0_SB_PAR
  VSS99  = GND
  CS1_B_N  = M_G_CPU0_SB_CS_N<3>
  VSS100  = GND
  RFU5  = TP_CHG_CPU0_DIMM2_FRU_5
  RFU6  = TP_CHG_CPU0_DIMM2_FRU_6
  VSS101  = GND
  CB6_B  = M_G_CPU0_SB_CB<6>
  VSS102  = GND
  CB7_B  = M_G_CPU0_SB_CB<7>
  VSS103  = GND
  DQS4_B_C  = M_G_CPU0_SB_DQS_DN<4>
  DQS4_B_T  = M_G_CPU0_SB_DQS_DP<4>
  VSS104  = GND
  CB2_B  = M_G_CPU0_SB_CB<2>
  VSS105  = GND
  CB3_B  = M_G_CPU0_SB_CB<3>
  VSS106  = GND
  DQ2_B  = M_G_CPU0_SB_DQ<2>
  VSS107  = GND
  DQ3_B  = M_G_CPU0_SB_DQ<3>
  VSS108  = GND
  \dqs5_b_c||tdqs5_b_c\  = M_G_CPU0_SB_DQS_DN<5>
  \dqs5_b_t||tdqs5_b_t\  = M_G_CPU0_SB_DQS_DP<5>
  VSS109  = GND
  DQ6_B  = M_G_CPU0_SB_DQ<6>
  VSS110  = GND
  DQ7_B  = M_G_CPU0_SB_DQ<7>
  VSS111  = GND
  DQ10_B  = M_G_CPU0_SB_DQ<10>
  VSS112  = GND
  DQ11_B  = M_G_CPU0_SB_DQ<11>
  VSS113  = GND
  \dqs6_b_c||tdqs6_b_c\  = M_G_CPU0_SB_DQS_DN<6>
  \dqs6_b_t||tdqs6_b_t\  = M_G_CPU0_SB_DQS_DP<6>
  VSS114  = GND
  DQ14_B  = M_G_CPU0_SB_DQ<14>
  VSS115  = GND
  DQ15_B  = M_G_CPU0_SB_DQ<15>
  VSS116  = GND
  DQ18_B  = M_G_CPU0_SB_DQ<18>
  VSS117  = GND
  DQ19_B  = M_G_CPU0_SB_DQ<19>
  VSS118  = GND
  \dqs7_b_c||tdqs7_b_c\  = M_G_CPU0_SB_DQS_DN<7>
  \dqs7_b_t||tdqs7_b_t\  = M_G_CPU0_SB_DQS_DP<7>
  VSS119  = GND
  DQ22_B  = M_G_CPU0_SB_DQ<22>
  VSS120  = GND
  DQ23_B  = M_G_CPU0_SB_DQ<23>
  VSS121  = GND
  DQ26_B  = M_G_CPU0_SB_DQ<26>
  VSS122  = GND
  DQ27_B  = M_G_CPU0_SB_DQ<27>
  VSS123  = GND
  \dqs8_b_c||tdqs8_b_c\  = M_G_CPU0_SB_DQS_DN<8>
  \dqs8_b_t||tdqs8_b_t\  = M_G_CPU0_SB_DQS_DP<8>
  VSS124  = GND
  DQ30_B  = M_G_CPU0_SB_DQ<30>
  VSS125  = GND
  DQ31_B  = M_G_CPU0_SB_DQ<31>
  VSS126  = GND
  G1  = GND
  G2  = GND
  G3  = GND

(kicad_pcb
	(version 20260206)
	(generator "pcbnew")
	(generator_version "10.0")
	(general
		(thickness 1.6)
		(legacy_teardrops no)
	)
	(paper "A4")
	(title_block
		(title "03242023_DA0F0TMBIJ0_F0T_Motherboard_J_brd_V01_OCP.brd")
		(comment 1 "Grand Teton / footprint 3833 of 6105 (J14), pads 138-182 of 291")
	)
	(layers
		(0 "F.Cu" signal "TOP")
		(4 "In1.Cu" signal "GND")
		(6 "In2.Cu" signal "IN1")
		(8 "In3.Cu" signal "GND1")
		(10 "In4.Cu" signal "IN2")
		(12 "In5.Cu" signal "GND2")
		(14 "In6.Cu" signal "IN3")
		(16 "In7.Cu" signal "GND3")
		(18 "In8.Cu" signal "VCC")
		(20 "In9.Cu" signal "VCC1")
		(22 "In10.Cu" signal "GND4")
		(24 "In11.Cu" signal "IN4")
		(26 "In12.Cu" signal "GND5")
		(28 "In13.Cu" signal "IN5")
		(30 "In14.Cu" signal "GND6")
		(32 "In15.Cu" signal "IN6")
		(34 "In16.Cu" signal "GND7")
		(2 "B.Cu" signal "BOTTOM")
		(9 "F.Adhes" user "F.Adhesive")
		(11 "B.Adhes" user "B.Adhesive")
		(13 "F.Paste" user "Package Geometry/Pastemask Top")
		(15 "B.Paste" user "Package Geometry/Pastemask Bottom")
		(5 "F.SilkS" user "Ref Des/Silkscreen Top")
		(7 "B.SilkS" user "Ref Des/Silkscreen Bottom")
		(1 "F.Mask" user "Board Geometry/Soldermask Top")
		(3 "B.Mask" user "Board Geometry/Soldermask Bottom")
		(17 "Dwgs.User" user "User.Drawings")
		(19 "Cmts.User" user "User.Comments")
		(21 "Eco1.User" user "User.Eco1")
		(23 "Eco2.User" user "User.Eco2")
		(25 "Edge.Cuts" user "Board Geometry/Outline")
		(27 "Margin" user)
		(31 "F.CrtYd" user "Package Geometry/Place Bound Top")
		(29 "B.CrtYd" user "Package Geometry/Place Bound Bottom")
		(35 "F.Fab" user "Ref Des/Assembly Top")
		(33 "B.Fab" user "Ref Des/Assembly Bottom")
	)
	(footprint ""
		(layer "F.Cu")
		(at 438.978548 -258.091686)
		(property "Reference" "J14"
			(at -3.683 -81.702148 0)
			(unlocked yes)
			(layer "F.SilkS")
			(effects
				(font
					(size 0.7874 0.5842)
					(thickness 0.1524)
				)
				(justify left)
			)
		)
		(property "Value" ""
			(at 0 0 0)
			(layer "F.Fab")
			(effects
				(font
					(size 1.27 1.27)
				)
			)
		)
		(duplicate_pad_numbers_are_jumpers no)
		(pad "138" smd rect
			(at -2.050034 58.224928 270)
			(size 0.519938 1.4986)
			(layers "F.Cu" "F.Mask" "F.Paste")
			(net "M_G_CPU0_SB_DQS_DN<3>")
		)
		(pad "139" smd rect
			(at -2.050034 59.075066 270)
			(size 0.519938 1.4986)
			(layers "F.Cu" "F.Mask" "F.Paste")
			(net "GND")
		)
		(pad "140" smd rect
			(at -2.050034 59.92495 270)
			(size 0.519938 1.4986)
			(layers "F.Cu" "F.Mask" "F.Paste")
			(net "M_G_CPU0_SB_DQ<28>")
		)
		(pad "141" smd rect
			(at -2.050034 60.775088 270)
			(size 0.519938 1.4986)
			(layers "F.Cu" "F.Mask" "F.Paste")
			(net "GND")
		)
		(pad "142" smd rect
			(at -2.050034 61.624972 270)
			(size 0.519938 1.4986)
			(layers "F.Cu" "F.Mask" "F.Paste")
			(net "M_G_CPU0_SB_DQ<29>")
		)
		(pad "143" smd rect
			(at -2.050034 62.47511 270)
			(size 0.519938 1.4986)
			(layers "F.Cu" "F.Mask" "F.Paste")
			(net "GND")
		)
		(pad "144" smd rect
			(at -2.050034 63.324994 270)
			(size 0.519938 1.4986)
			(layers "F.Cu" "F.Mask" "F.Paste")
			(net "TP_CHG_CPU0_DIMM2_FRU_1")
		)
		(pad "145" smd rect
			(at 2.050034 -63.324994 270)
			(size 0.519938 1.4986)
			(layers "F.Cu" "F.Mask" "F.Paste")
			(net "P12V_S3_AUX_CPU0_NVDIMM")
		)
		(pad "146" smd rect
			(at 2.050034 -62.47511 270)
			(size 0.519938 1.4986)
			(layers "F.Cu" "F.Mask" "F.Paste")
			(net "P12V_S3_AUX_CPU0_NVDIMM")
		)
		(pad "147" smd rect
			(at 2.050034 -61.624972 270)
			(size 0.519938 1.4986)
			(layers "F.Cu" "F.Mask" "F.Paste")
			(net "PWRGD_CHG_CPU0_DIMM2")
		)
		(pad "148" smd rect
			(at 2.050034 -60.775088 270)
			(size 0.519938 1.4986)
			(layers "F.Cu" "F.Mask" "F.Paste")
			(net "PD_CHG_CPU0_DIMM2_SAA")
		)
		(pad "149" smd rect
			(at 2.050034 -59.92495 270)
			(size 0.519938 1.4986)
			(layers "F.Cu" "F.Mask" "F.Paste")
			(net "TP_CHG_CPU0_DIMM2_FRU_2")
		)
		(pad "150" smd rect
			(at 2.050034 -59.075066 270)
			(size 0.519938 1.4986)
			(layers "F.Cu" "F.Mask" "F.Paste")
			(net "TP_CHG_CPU0_DIMM2_FRU_3")
		)
		(pad "151" smd rect
			(at 2.050034 -58.224928 270)
			(size 0.519938 1.4986)
			(layers "F.Cu" "F.Mask" "F.Paste")
			(net "GND")
		)
		(pad "152" smd rect
			(at 2.050034 -57.375044 270)
			(size 0.519938 1.4986)
			(layers "F.Cu" "F.Mask" "F.Paste")
			(net "M_G_CPU0_SA_DQ<2>")
		)
		(pad "153" smd rect
			(at 2.050034 -56.524906 270)
			(size 0.519938 1.4986)
			(layers "F.Cu" "F.Mask" "F.Paste")
			(net "GND")
		)
		(pad "154" smd rect
			(at 2.050034 -55.675022 270)
			(size 0.519938 1.4986)
			(layers "F.Cu" "F.Mask" "F.Paste")
			(net "M_G_CPU0_SA_DQ<3>")
		)
		(pad "155" smd rect
			(at 2.050034 -54.824884 270)
			(size 0.519938 1.4986)
			(layers "F.Cu" "F.Mask" "F.Paste")
			(net "GND")
		)
		(pad "156" smd rect
			(at 2.050034 -53.975 270)
			(size 0.519938 1.4986)
			(layers "F.Cu" "F.Mask" "F.Paste")
			(net "M_G_CPU0_SA_DQS_DN<5>")
		)
		(pad "157" smd rect
			(at 2.050034 -53.125116 270)
			(size 0.519938 1.4986)
			(layers "F.Cu" "F.Mask" "F.Paste")
			(net "M_G_CPU0_SA_DQS_DP<5>")
		)
		(pad "158" smd rect
			(at 2.050034 -52.274978 270)
			(size 0.519938 1.4986)
			(layers "F.Cu" "F.Mask" "F.Paste")
			(net "GND")
		)
		(pad "159" smd rect
			(at 2.050034 -51.425094 270)
			(size 0.519938 1.4986)
			(layers "F.Cu" "F.Mask" "F.Paste")
			(net "M_G_CPU0_SA_DQ<6>")
		)
		(pad "160" smd rect
			(at 2.050034 -50.574956 270)
			(size 0.519938 1.4986)
			(layers "F.Cu" "F.Mask" "F.Paste")
			(net "GND")
		)
		(pad "161" smd rect
			(at 2.050034 -49.725072 270)
			(size 0.519938 1.4986)
			(layers "F.Cu" "F.Mask" "F.Paste")
			(net "M_G_CPU0_SA_DQ<7>")
		)
		(pad "162" smd rect
			(at 2.050034 -48.874934 270)
			(size 0.519938 1.4986)
			(layers "F.Cu" "F.Mask" "F.Paste")
			(net "GND")
		)
		(pad "163" smd rect
			(at 2.050034 -48.02505 270)
			(size 0.519938 1.4986)
			(layers "F.Cu" "F.Mask" "F.Paste")
			(net "M_G_CPU0_SA_DQ<10>")
		)
		(pad "164" smd rect
			(at 2.050034 -47.174912 270)
			(size 0.519938 1.4986)
			(layers "F.Cu" "F.Mask" "F.Paste")
			(net "GND")
		)
		(pad "165" smd rect
			(at 2.050034 -46.325028 270)
			(size 0.519938 1.4986)
			(layers "F.Cu" "F.Mask" "F.Paste")
			(net "M_G_CPU0_SA_DQ<11>")
		)
		(pad "166" smd rect
			(at 2.050034 -45.47489 270)
			(size 0.519938 1.4986)
			(layers "F.Cu" "F.Mask" "F.Paste")
			(net "GND")
		)
		(pad "167" smd rect
			(at 2.050034 -44.625006 270)
			(size 0.519938 1.4986)
			(layers "F.Cu" "F.Mask" "F.Paste")
			(net "M_G_CPU0_SA_DQS_DN<6>")
		)
		(pad "168" smd rect
			(at 2.050034 -43.775122 270)
			(size 0.519938 1.4986)
			(layers "F.Cu" "F.Mask" "F.Paste")
			(net "M_G_CPU0_SA_DQS_DP<6>")
		)
		(pad "169" smd rect
			(at 2.050034 -42.924984 270)
			(size 0.519938 1.4986)
			(layers "F.Cu" "F.Mask" "F.Paste")
			(net "GND")
		)
		(pad "170" smd rect
			(at 2.050034 -42.0751 270)
			(size 0.519938 1.4986)
			(layers "F.Cu" "F.Mask" "F.Paste")
			(net "M_G_CPU0_SA_DQ<14>")
		)
		(pad "171" smd rect
			(at 2.050034 -41.224962 270)
			(size 0.519938 1.4986)
			(layers "F.Cu" "F.Mask" "F.Paste")
			(net "GND")
		)
		(pad "172" smd rect
			(at 2.050034 -40.375078 270)
			(size 0.519938 1.4986)
			(layers "F.Cu" "F.Mask" "F.Paste")
			(net "M_G_CPU0_SA_DQ<15>")
		)
		(pad "173" smd rect
			(at 2.050034 -39.52494 270)
			(size 0.519938 1.4986)
			(layers "F.Cu" "F.Mask" "F.Paste")
			(net "GND")
		)
		(pad "174" smd rect
			(at 2.050034 -38.675056 270)
			(size 0.519938 1.4986)
			(layers "F.Cu" "F.Mask" "F.Paste")
			(net "M_G_CPU0_SA_DQ<18>")
		)
		(pad "175" smd rect
			(at 2.050034 -37.824918 270)
			(size 0.519938 1.4986)
			(layers "F.Cu" "F.Mask" "F.Paste")
			(net "GND")
		)
		(pad "176" smd rect
			(at 2.050034 -36.975034 270)
			(size 0.519938 1.4986)
			(layers "F.Cu" "F.Mask" "F.Paste")
			(net "M_G_CPU0_SA_DQ<19>")
		)
		(pad "177" smd rect
			(at 2.050034 -36.124896 270)
			(size 0.519938 1.4986)
			(layers "F.Cu" "F.Mask" "F.Paste")
			(net "GND")
		)
		(pad "178" smd rect
			(at 2.050034 -35.275012 270)
			(size 0.519938 1.4986)
			(layers "F.Cu" "F.Mask" "F.Paste")
			(net "M_G_CPU0_SA_DQS_DN<7>")
		)
		(pad "179" smd rect
			(at 2.050034 -34.425128 270)
			(size 0.519938 1.4986)
			(layers "F.Cu" "F.Mask" "F.Paste")
			(net "M_G_CPU0_SA_DQS_DP<7>")
		)
		(pad "180" smd rect
			(at 2.050034 -33.57499 270)
			(size 0.519938 1.4986)
			(layers "F.Cu" "F.Mask" "F.Paste")
			(net "GND")
		)
		(pad "181" smd rect
			(at 2.050034 -32.725106 270)
			(size 0.519938 1.4986)
			(layers "F.Cu" "F.Mask" "F.Paste")
			(net "M_G_CPU0_SA_DQ<22>")
		)
		(pad "182" smd rect
			(at 2.050034 -31.874968 270)
			(size 0.519938 1.4986)
			(layers "F.Cu" "F.Mask" "F.Paste")
			(net "GND")
		)
	)
)
